(kicad_pcb
	(version 20260206)
	(generator "pcbnew")
	(generator_version "10.0")
	(general
		(thickness 1.6)
		(legacy_teardrops no)
	)
	(paper "A4")
	(title_block
		(title "04192023_DAF0TMB3IC0_F0TG_MB_C_brd_V02_OCP.brd")
		(comment 1 "Grand Teton / footprints 24-29 of 8354")
	)
	(layers
		(0 "F.Cu" signal "TOP")
		(4 "In1.Cu" signal "GND")
		(6 "In2.Cu" signal "IN1")
		(8 "In3.Cu" signal "GND1")
		(10 "In4.Cu" signal "IN2")
		(12 "In5.Cu" signal "GND2")
		(14 "In6.Cu" signal "IN3")
		(16 "In7.Cu" signal "GND3")
		(18 "In8.Cu" signal "VCC")
		(20 "In9.Cu" signal "VCC1")
		(22 "In10.Cu" signal "GND4")
		(24 "In11.Cu" signal "IN4")
		(26 "In12.Cu" signal "GND5")
		(28 "In13.Cu" signal "IN5")
		(30 "In14.Cu" signal "GND6")
		(32 "In15.Cu" signal "IN6")
		(34 "In16.Cu" signal "GND7")
		(2 "B.Cu" signal "BOTTOM")
		(9 "F.Adhes" user "F.Adhesive")
		(11 "B.Adhes" user "B.Adhesive")
		(13 "F.Paste" user "Package Geometry/Pastemask Top")
		(15 "B.Paste" user "Package Geometry/Pastemask Bottom")
		(5 "F.SilkS" user "Ref Des/Silkscreen Top")
		(7 "B.SilkS" user "Ref Des/Silkscreen Bottom")
		(1 "F.Mask" user "Board Geometry/Soldermask Top")
		(3 "B.Mask" user "Board Geometry/Soldermask Bottom")
		(17 "Dwgs.User" user "User.Drawings")
		(19 "Cmts.User" user "User.Comments")
		(21 "Eco1.User" user "User.Eco1")
		(23 "Eco2.User" user "User.Eco2")
		(25 "Edge.Cuts" user "Board Geometry/Outline")
		(27 "Margin" user)
		(31 "F.CrtYd" user "Package Geometry/Place Bound Top")
		(29 "B.CrtYd" user "Package Geometry/Place Bound Bottom")
		(35 "F.Fab" user "Ref Des/Assembly Top")
		(33 "B.Fab" user "Ref Des/Assembly Bottom")
	)
	(footprint ""
		(layer "F.Cu")
		(at 493.36833 -298.352718 90)
		(property "Reference" "X10"
			(at -1.985264 1.132586 0)
			(unlocked yes)
			(layer "F.SilkS")
			(effects
				(font
					(size 0.7874 0.5842)
					(thickness 0.1524)
				)
				(justify left)
			)
		)
		(property "Value" ""
			(at 0 0 90)
			(layer "F.Fab")
			(effects
				(font
					(size 1.27 1.27)
				)
			)
		)
		(property "User Part Number" "N_A"
			(at 1.30175 1.27 180)
			(unlocked yes)
			(layer "Cmts.User")
			(hide yes)
			(effects
				(font
					(size 0.635 0.4064)
					(thickness 0.1524)
				)
			)
		)
		(property "Device Type" "TP_TDR_4P_FTS_TH-TP_TDR_4P_DIP,EMPTY,TP15"
			(at 1.30175 1.27 180)
			(unlocked yes)
			(layer "F.Fab")
			(hide yes)
			(effects
				(font
					(size 0.635 0.4064)
					(thickness 0.1524)
				)
			)
		)
		(duplicate_pad_numbers_are_jumpers no)
		(fp_line
			(start 2.54 -1.27)
			(end 0 -1.27)
			(stroke
				(width 0.1524)
				(type default)
			)
			(layer "F.SilkS")
		)
		(fp_line
			(start 0 -1.27)
			(end 0 -0.635)
			(stroke
				(width 0.1524)
				(type default)
			)
			(layer "F.SilkS")
		)
		(fp_line
			(start 2.54 -1.1303)
			(end 2.54 -1.27)
			(stroke
				(width 0.1524)
				(type default)
			)
			(layer "F.SilkS")
		)
		(fp_line
			(start 0 0.635)
			(end 0 1.905)
			(stroke
				(width 0.1524)
				(type default)
			)
			(layer "F.SilkS")
		)
		(fp_line
			(start 2.54 1.4097)
			(end 2.54 1.1303)
			(stroke
				(width 0.1524)
				(type default)
			)
			(layer "F.SilkS")
		)
		(fp_line
			(start 0 3.175)
			(end 0 3.81)
			(stroke
				(width 0.1524)
				(type default)
			)
			(layer "F.SilkS")
		)
		(fp_line
			(start 2.54 3.81)
			(end 2.54 3.6703)
			(stroke
				(width 0.1524)
				(type default)
			)
			(layer "F.SilkS")
		)
		(fp_line
			(start 0 3.81)
			(end 2.54 3.81)
			(stroke
				(width 0.1524)
				(type default)
			)
			(layer "F.SilkS")
		)
		(fp_poly
			(pts
				(xy -0.761746 0) (xy -2.285746 0.762) (xy -2.285746 -0.762)
			)
			(stroke
				(width 0)
				(type default)
			)
			(fill yes)
			(layer "F.SilkS")
		)
		(fp_line
			(start 2.54 -1.27)
			(end 0 -1.27)
			(stroke
				(width 0.1)
				(type default)
			)
			(layer "F.Fab")
		)
		(fp_line
			(start 0 -1.27)
			(end 0 3.81)
			(stroke
				(width 0.1)
				(type default)
			)
			(layer "F.Fab")
		)
		(fp_line
			(start 2.54 3.81)
			(end 2.54 -1.27)
			(stroke
				(width 0.1)
				(type default)
			)
			(layer "F.Fab")
		)
		(fp_line
			(start 0 3.81)
			(end 2.54 3.81)
			(stroke
				(width 0.1)
				(type default)
			)
			(layer "F.Fab")
		)
		(fp_poly
			(pts
				(xy -0.761746 0) (xy -2.285746 -0.762) (xy -2.285746 0.762)
			)
			(stroke
				(width 0)
				(type default)
			)
			(fill yes)
			(layer "F.Fab")
		)
		(pad "1" thru_hole circle
			(at 0 0 90)
			(size 1.0033 1.0033)
			(drill 0.249936)
			(layers "*.Cu" "*.Mask")
			(remove_unused_layers no)
			(net "TDR_DIFF_80_IN3_DN")
			(clearance 0.10795)
			(thermal_gap 0.10795)
			(padstack
				(mode front_inner_back)
				(layer "Inner"
					(shape circle)
					(size 0.8001 0.8001)
					(clearance 0.1524)
				)
				(layer "B.Cu"
					(shape circle)
					(size 1.0033 1.0033)
					(clearance 0.10795)
				)
			)
		)
		(pad "2" thru_hole circle
			(at 2.54 0 90)
			(size 1.9939 1.9939)
			(drill 0.249936)
			(layers "*.Cu" "*.Mask")
			(remove_unused_layers no)
			(net "T1_GND")
			(clearance 0.10795)
			(thermal_gap 0.10795)
			(padstack
				(mode front_inner_back)
				(layer "Inner"
					(shape circle)
					(size 0.8001 0.8001)
					(clearance 0.1524)
				)
				(layer "B.Cu"
					(shape circle)
					(size 1.9939 1.9939)
					(clearance 0.10795)
				)
			)
		)
		(pad "3" thru_hole circle
			(at 2.54 2.54 90)
			(size 1.9939 1.9939)
			(drill 0.249936)
			(layers "*.Cu" "*.Mask")
			(remove_unused_layers no)
			(net "T1_GND")
			(clearance 0.10795)
			(thermal_gap 0.10795)
			(padstack
				(mode front_inner_back)
				(layer "Inner"
					(shape circle)
					(size 0.8001 0.8001)
					(clearance 0.1524)
				)
				(layer "B.Cu"
					(shape circle)
					(size 1.9939 1.9939)
					(clearance 0.10795)
				)
			)
		)
		(pad "4" thru_hole circle
			(at 0 2.54 90)
			(size 1.0033 1.0033)
			(drill 0.249936)
			(layers "*.Cu" "*.Mask")
			(remove_unused_layers no)
			(net "TDR_DIFF_80_IN3_DP")
			(clearance 0.10795)
			(thermal_gap 0.10795)
			(padstack
				(mode front_inner_back)
				(layer "Inner"
					(shape circle)
					(size 0.8001 0.8001)
					(clearance 0.1524)
				)
				(layer "B.Cu"
					(shape circle)
					(size 1.0033 1.0033)
					(clearance 0.10795)
				)
			)
		)
	)
	(footprint ""
		(layer "F.Cu")
		(at 328.092308 -102.52075)
		(property "Reference" "C1096"
			(at 0 0 0)
			(layer "F.SilkS")
			(hide yes)
			(effects
				(font
					(size 1.27 1.27)
				)
			)
		)
		(property "Value" ""
			(at 0 0 0)
			(layer "F.Fab")
			(effects
				(font
					(size 1.27 1.27)
				)
			)
		)
		(duplicate_pad_numbers_are_jumpers no)
		(fp_line
			(start -0.7874 -0.4064)
			(end 0.7874 -0.4064)
			(stroke
				(width 0.1524)
				(type default)
			)
			(layer "F.SilkS")
		)
		(fp_line
			(start -0.7874 0.4064)
			(end -0.7874 -0.4064)
			(stroke
				(width 0.1524)
				(type default)
			)
			(layer "F.SilkS")
		)
		(fp_line
			(start 0.7874 -0.4064)
			(end 0.7874 0.4064)
			(stroke
				(width 0.1524)
				(type default)
			)
			(layer "F.SilkS")
		)
		(fp_line
			(start 0.7874 0.4064)
			(end -0.7874 0.4064)
			(stroke
				(width 0.1524)
				(type default)
			)
			(layer "F.SilkS")
		)
		(fp_line
			(start -0.67945 -0.305054)
			(end -0.12065 -0.305054)
			(stroke
				(width 0.1)
				(type default)
			)
			(layer "F.Fab")
		)
		(fp_line
			(start -0.67945 0.3048)
			(end -0.67945 -0.305054)
			(stroke
				(width 0.1)
				(type default)
			)
			(layer "F.Fab")
		)
		(fp_line
			(start -0.12065 -0.305054)
			(end -0.12065 -0.2794)
			(stroke
				(width 0.1)
				(type default)
			)
			(layer "F.Fab")
		)
		(fp_line
			(start -0.12065 -0.2794)
			(end 0.12065 -0.2794)
			(stroke
				(width 0.1)
				(type default)
			)
			(layer "F.Fab")
		)
		(fp_line
			(start -0.12065 0.2794)
			(end -0.12065 0.3048)
			(stroke
				(width 0.1)
				(type default)
			)
			(layer "F.Fab")
		)
		(fp_line
			(start -0.12065 0.3048)
			(end -0.67945 0.3048)
			(stroke
				(width 0.1)
				(type default)
			)
			(layer "F.Fab")
		)
		(fp_line
			(start 0.120396 0.2794)
			(end -0.12065 0.2794)
			(stroke
				(width 0.1)
				(type default)
			)
			(layer "F.Fab")
		)
		(fp_line
			(start 0.120396 0.3048)
			(end 0.120396 0.2794)
			(stroke
				(width 0.1)
				(type default)
			)
			(layer "F.Fab")
		)
		(fp_line
			(start 0.12065 -0.3048)
			(end 0.67945 -0.3048)
			(stroke
				(width 0.1)
				(type default)
			)
			(layer "F.Fab")
		)
		(fp_line
			(start 0.12065 -0.2794)
			(end 0.12065 -0.3048)
			(stroke
				(width 0.1)
				(type default)
			)
			(layer "F.Fab")
		)
		(fp_line
			(start 0.67945 -0.3048)
			(end 0.67945 0.3048)
			(stroke
				(width 0.1)
				(type default)
			)
			(layer "F.Fab")
		)
		(fp_line
			(start 0.67945 0.3048)
			(end 0.120396 0.3048)
			(stroke
				(width 0.1)
				(type default)
			)
			(layer "F.Fab")
		)
		(pad "1" smd circle
			(at -0.40005 0)
			(size 0 0)
			(layers "F.Cu" "F.Mask" "F.Paste")
			(net "P3V3_AUX")
		)
		(pad "2" smd circle
			(at 0.40005 0)
			(size 0 0)
			(layers "F.Cu" "F.Mask" "F.Paste")
			(net "GND")
		)
	)
	(footprint ""
		(layer "F.Cu")
		(at 218.567 -100.457)
		(property "Reference" "C9008"
			(at 0 0 0)
			(layer "F.SilkS")
			(hide yes)
			(effects
				(font
					(size 1.27 1.27)
				)
			)
		)
		(property "Value" ""
			(at 0 0 0)
			(layer "F.Fab")
			(effects
				(font
					(size 1.27 1.27)
				)
			)
		)
		(duplicate_pad_numbers_are_jumpers no)
		(fp_line
			(start -0.7874 -0.4064)
			(end 0.7874 -0.4064)
			(stroke
				(width 0.1524)
				(type default)
			)
			(layer "F.SilkS")
		)
		(fp_line
			(start -0.7874 0.4064)
			(end -0.7874 -0.4064)
			(stroke
				(width 0.1524)
				(type default)
			)
			(layer "F.SilkS")
		)
		(fp_line
			(start 0.7874 -0.4064)
			(end 0.7874 0.4064)
			(stroke
				(width 0.1524)
				(type default)
			)
			(layer "F.SilkS")
		)
		(fp_line
			(start 0.7874 0.4064)
			(end -0.7874 0.4064)
			(stroke
				(width 0.1524)
				(type default)
			)
			(layer "F.SilkS")
		)
		(fp_line
			(start -0.67945 -0.305054)
			(end -0.12065 -0.305054)
			(stroke
				(width 0.1)
				(type default)
			)
			(layer "F.Fab")
		)
		(fp_line
			(start -0.67945 0.3048)
			(end -0.67945 -0.305054)
			(stroke
				(width 0.1)
				(type default)
			)
			(layer "F.Fab")
		)
		(fp_line
			(start -0.12065 -0.305054)
			(end -0.12065 -0.2794)
			(stroke
				(width 0.1)
				(type default)
			)
			(layer "F.Fab")
		)
		(fp_line
			(start -0.12065 -0.2794)
			(end 0.12065 -0.2794)
			(stroke
				(width 0.1)
				(type default)
			)
			(layer "F.Fab")
		)
		(fp_line
			(start -0.12065 0.2794)
			(end -0.12065 0.3048)
			(stroke
				(width 0.1)
				(type default)
			)
			(layer "F.Fab")
		)
		(fp_line
			(start -0.12065 0.3048)
			(end -0.67945 0.3048)
			(stroke
				(width 0.1)
				(type default)
			)
			(layer "F.Fab")
		)
		(fp_line
			(start 0.120396 0.2794)
			(end -0.12065 0.2794)
			(stroke
				(width 0.1)
				(type default)
			)
			(layer "F.Fab")
		)
		(fp_line
			(start 0.120396 0.3048)
			(end 0.120396 0.2794)
			(stroke
				(width 0.1)
				(type default)
			)
			(layer "F.Fab")
		)
		(fp_line
			(start 0.12065 -0.3048)
			(end 0.67945 -0.3048)
			(stroke
				(width 0.1)
				(type default)
			)
			(layer "F.Fab")
		)
		(fp_line
			(start 0.12065 -0.2794)
			(end 0.12065 -0.3048)
			(stroke
				(width 0.1)
				(type default)
			)
			(layer "F.Fab")
		)
		(fp_line
			(start 0.67945 -0.3048)
			(end 0.67945 0.3048)
			(stroke
				(width 0.1)
				(type default)
			)
			(layer "F.Fab")
		)
		(fp_line
			(start 0.67945 0.3048)
			(end 0.120396 0.3048)
			(stroke
				(width 0.1)
				(type default)
			)
			(layer "F.Fab")
		)
		(pad "1" smd circle
			(at -0.40005 0)
			(size 0 0)
			(layers "F.Cu" "F.Mask" "F.Paste")
			(net "P3V3_AUX")
		)
		(pad "2" smd circle
			(at 0.40005 0)
			(size 0 0)
			(layers "F.Cu" "F.Mask" "F.Paste")
			(net "GND")
		)
	)
	(footprint ""
		(layer "F.Cu")
		(at 163.582096 -102.984046 180)
		(property "Reference" "R6186"
			(at 0 0 180)
			(layer "F.SilkS")
			(hide yes)
			(effects
				(font
					(size 1.27 1.27)
				)
			)
		)
		(property "Value" ""
			(at 0 0 180)
			(layer "F.Fab")
			(effects
				(font
					(size 1.27 1.27)
				)
			)
		)
		(duplicate_pad_numbers_are_jumpers no)
		(fp_line
			(start 0.7874 0.4064)
			(end -0.7874 0.4064)
			(stroke
				(width 0.1524)
				(type default)
			)
			(layer "F.SilkS")
		)
		(fp_line
			(start 0.7874 -0.4064)
			(end 0.7874 0.4064)
			(stroke
				(width 0.1524)
				(type default)
			)
			(layer "F.SilkS")
		)
		(fp_line
			(start -0.7874 0.4064)
			(end -0.7874 -0.4064)
			(stroke
				(width 0.1524)
				(type default)
			)
			(layer "F.SilkS")
		)
		(fp_line
			(start -0.7874 -0.4064)
			(end 0.7874 -0.4064)
			(stroke
				(width 0.1524)
				(type default)
			)
			(layer "F.SilkS")
		)
		(fp_line
			(start 0.67945 0.3048)
			(end 0.120396 0.3048)
			(stroke
				(width 0.1)
				(type default)
			)
			(layer "F.Fab")
		)
		(fp_line
			(start 0.67945 -0.3048)
			(end 0.67945 0.3048)
			(stroke
				(width 0.1)
				(type default)
			)
			(layer "F.Fab")
		)
		(fp_line
			(start 0.12065 -0.2794)
			(end 0.12065 -0.3048)
			(stroke
				(width 0.1)
				(type default)
			)
			(layer "F.Fab")
		)
		(fp_line
			(start 0.12065 -0.3048)
			(end 0.67945 -0.3048)
			(stroke
				(width 0.1)
				(type default)
			)
			(layer "F.Fab")
		)
		(fp_line
			(start 0.120396 0.3048)
			(end 0.120396 0.2794)
			(stroke
				(width 0.1)
				(type default)
			)
			(layer "F.Fab")
		)
		(fp_line
			(start 0.120396 0.2794)
			(end -0.12065 0.2794)
			(stroke
				(width 0.1)
				(type default)
			)
			(layer "F.Fab")
		)
		(fp_line
			(start -0.12065 0.3048)
			(end -0.67945 0.3048)
			(stroke
				(width 0.1)
				(type default)
			)
			(layer "F.Fab")
		)
		(fp_line
			(start -0.12065 0.2794)
			(end -0.12065 0.3048)
			(stroke
				(width 0.1)
				(type default)
			)
			(layer "F.Fab")
		)
		(fp_line
			(start -0.12065 -0.2794)
			(end 0.12065 -0.2794)
			(stroke
				(width 0.1)
				(type default)
			)
			(layer "F.Fab")
		)
		(fp_line
			(start -0.12065 -0.305054)
			(end -0.12065 -0.2794)
			(stroke
				(width 0.1)
				(type default)
			)
			(layer "F.Fab")
		)
		(fp_line
			(start -0.67945 0.3048)
			(end -0.67945 -0.305054)
			(stroke
				(width 0.1)
				(type default)
			)
			(layer "F.Fab")
		)
		(fp_line
			(start -0.67945 -0.305054)
			(end -0.12065 -0.305054)
			(stroke
				(width 0.1)
				(type default)
			)
			(layer "F.Fab")
		)
		(pad "1" smd circle
			(at -0.40005 0 180)
			(size 0 0)
			(layers "F.Cu" "F.Mask" "F.Paste")
			(net "FM_SEC_MUX_OE_N")
		)
		(pad "2" smd circle
			(at 0.40005 0 180)
			(size 0 0)
			(layers "F.Cu" "F.Mask" "F.Paste")
			(net "P3V3_AUX")
		)
	)
	(footprint ""
		(layer "F.Cu")
		(at 65.50914 -346.87129 -90)
		(property "Reference" "PC407_4"
			(at 0 0 270)
			(layer "F.SilkS")
			(hide yes)
			(effects
				(font
					(size 1.27 1.27)
				)
			)
		)
		(property "Value" ""
			(at 0 0 270)
			(layer "F.Fab")
			(effects
				(font
					(size 1.27 1.27)
				)
			)
		)
		(duplicate_pad_numbers_are_jumpers no)
		(fp_line
			(start -0.7874 0.4064)
			(end -0.7874 -0.4064)
			(stroke
				(width 0.1524)
				(type default)
			)
			(layer "F.SilkS")
		)
		(fp_line
			(start 0.7874 0.4064)
			(end -0.7874 0.4064)
			(stroke
				(width 0.1524)
				(type default)
			)
			(layer "F.SilkS")
		)
		(fp_line
			(start -0.7874 -0.4064)
			(end 0.7874 -0.4064)
			(stroke
				(width 0.1524)
				(type default)
			)
			(layer "F.SilkS")
		)
		(fp_line
			(start 0.7874 -0.4064)
			(end 0.7874 0.4064)
			(stroke
				(width 0.1524)
				(type default)
			)
			(layer "F.SilkS")
		)
		(fp_line
			(start -0.67945 0.3048)
			(end -0.67945 -0.305054)
			(stroke
				(width 0.1)
				(type default)
			)
			(layer "F.Fab")
		)
		(fp_line
			(start -0.12065 0.3048)
			(end -0.67945 0.3048)
			(stroke
				(width 0.1)
				(type default)
			)
			(layer "F.Fab")
		)
		(fp_line
			(start 0.120396 0.3048)
			(end 0.120396 0.2794)
			(stroke
				(width 0.1)
				(type default)
			)
			(layer "F.Fab")
		)
		(fp_line
			(start 0.67945 0.3048)
			(end 0.120396 0.3048)
			(stroke
				(width 0.1)
				(type default)
			)
			(layer "F.Fab")
		)
		(fp_line
			(start -0.12065 0.2794)
			(end -0.12065 0.3048)
			(stroke
				(width 0.1)
				(type default)
			)
			(layer "F.Fab")
		)
		(fp_line
			(start 0.120396 0.2794)
			(end -0.12065 0.2794)
			(stroke
				(width 0.1)
				(type default)
			)
			(layer "F.Fab")
		)
		(fp_line
			(start -0.12065 -0.2794)
			(end 0.12065 -0.2794)
			(stroke
				(width 0.1)
				(type default)
			)
			(layer "F.Fab")
		)
		(fp_line
			(start 0.12065 -0.2794)
			(end 0.12065 -0.3048)
			(stroke
				(width 0.1)
				(type default)
			)
			(layer "F.Fab")
		)
		(fp_line
			(start 0.12065 -0.3048)
			(end 0.67945 -0.3048)
			(stroke
				(width 0.1)
				(type default)
			)
			(layer "F.Fab")
		)
		(fp_line
			(start 0.67945 -0.3048)
			(end 0.67945 0.3048)
			(stroke
				(width 0.1)
				(type default)
			)
			(layer "F.Fab")
		)
		(fp_line
			(start -0.67945 -0.305054)
			(end -0.12065 -0.305054)
			(stroke
				(width 0.1)
				(type default)
			)
			(layer "F.Fab")
		)
		(fp_line
			(start -0.12065 -0.305054)
			(end -0.12065 -0.2794)
			(stroke
				(width 0.1)
				(type default)
			)
			(layer "F.Fab")
		)
		(pad "1" smd circle
			(at -0.40005 0 270)
			(size 0 0)
			(layers "F.Cu" "F.Mask" "F.Paste")
			(net "SW_P12V_AUX_PVDDCR_CPU1_P1_FLT")
		)
		(pad "2" smd circle
			(at 0.40005 0 270)
			(size 0 0)
			(layers "F.Cu" "F.Mask" "F.Paste")
			(net "GND")
		)
	)
	(footprint ""
		(layer "F.Cu")
		(at 433.05222 -418.942266 180)
		(property "Reference" ""
			(at 0 0 180)
			(layer "F.SilkS")
			(hide yes)
			(effects
				(font
					(size 1.27 1.27)
				)
			)
		)
		(property "Value" ""
			(at 0 0 180)
			(layer "F.Fab")
			(effects
				(font
					(size 1.27 1.27)
				)
			)
		)
		(duplicate_pad_numbers_are_jumpers no)
		(pad "1" smd circle
			(at 0 0 180)
			(size 0.9906 0.9906)
			(layers "F.Cu" "F.Mask" "F.Paste")
			(net "Net_2241")
		)
		(zone
			(layer "F.Cu")
			(hatch none 0.5)
			(connect_pads
				(clearance 0)
			)
			(min_thickness 0.25)
			(keepout
				(tracks not_allowed)
				(vias allowed)
				(pads allowed)
				(copperpour not_allowed)
				(footprints allowed)
			)
			(placement
				(enabled no)
				(sheetname "")
			)
			(fill
				(thermal_gap 0.5)
				(thermal_bridge_width 0.5)
				(island_removal_mode 0)
			)
			(polygon
				(pts
					(arc
						(start 434.67782 -418.942266)
						(mid 431.42662 -418.942266)
						(end 434.67782 -418.942266)
					)
				)
			)
		)
	)
)
